(kicad_pcb
	(version 20260206)
	(generator "pcbnew")
	(generator_version "10.0")
	(general
		(thickness 1.6)
		(legacy_teardrops no)
	)
	(paper "A4")
	(title_block
		(title "Wiwynn_Tioga_Pass_MB.brd")
		(comment 1 "Tioga Pass / footprints 2205-2212 of 4770")
	)
	(layers
		(0 "F.Cu" signal "TOP")
		(4 "In1.Cu" signal "L2GND")
		(6 "In2.Cu" signal "L3")
		(8 "In3.Cu" signal "L4GND")
		(10 "In4.Cu" signal "L5")
		(12 "In5.Cu" signal "L6GND")
		(14 "In6.Cu" signal "L7VCC")
		(16 "In7.Cu" signal "L8VCC")
		(18 "In8.Cu" signal "L9GND")
		(20 "In9.Cu" signal "L10")
		(22 "In10.Cu" signal "L11GND")
		(24 "In11.Cu" signal "L12")
		(26 "In12.Cu" signal "L13GND")
		(2 "B.Cu" signal "BOTTOM")
		(9 "F.Adhes" user "F.Adhesive")
		(11 "B.Adhes" user "B.Adhesive")
		(13 "F.Paste" user "Package Geometry/Pastemask Top")
		(15 "B.Paste" user "Package Geometry/Pastemask Bottom")
		(5 "F.SilkS" user "Ref Des/Silkscreen Top")
		(7 "B.SilkS" user "Ref Des/Silkscreen Bottom")
		(1 "F.Mask" user "Board Geometry/Soldermask Top")
		(3 "B.Mask" user "Board Geometry/Soldermask Bottom")
		(17 "Dwgs.User" user "User.Drawings")
		(19 "Cmts.User" user "User.Comments")
		(21 "Eco1.User" user "User.Eco1")
		(23 "Eco2.User" user "User.Eco2")
		(25 "Edge.Cuts" user "Board Geometry/Outline")
		(27 "Margin" user)
		(31 "F.CrtYd" user "Package Geometry/Place Bound Top")
		(29 "B.CrtYd" user "Package Geometry/Place Bound Bottom")
		(35 "F.Fab" user "Ref Des/Assembly Top")
		(33 "B.Fab" user "Ref Des/Assembly Bottom")
	)
	(footprint ""
		(layer "F.Cu")
		(at 6.35 -125.095 90)
		(property "Reference" "R1B15"
			(at 0 0 90)
			(layer "F.SilkS")
			(hide yes)
			(effects
				(font
					(size 1.27 1.27)
				)
			)
		)
		(property "Value" ""
			(at 0 0 90)
			(layer "F.Fab")
			(effects
				(font
					(size 1.27 1.27)
				)
			)
		)
		(duplicate_pad_numbers_are_jumpers no)
		(fp_poly
			(pts
				(xy -0.2794 -0.1016) (xy 0.2794 -0.1016) (xy 0.2794 0.9906) (xy -0.2794 0.9906)
			)
			(stroke
				(width 0)
				(type default)
			)
			(fill no)
			(layer "F.CrtYd")
		)
		(fp_line
			(start 0.2794 -0.1016)
			(end -0.2794 -0.1016)
			(stroke
				(width 0.1)
				(type default)
			)
			(layer "F.Fab")
		)
		(fp_line
			(start -0.2794 -0.1016)
			(end -0.2794 0.9906)
			(stroke
				(width 0.1)
				(type default)
			)
			(layer "F.Fab")
		)
		(fp_line
			(start 0.2794 0.9906)
			(end 0.2794 -0.1016)
			(stroke
				(width 0.1)
				(type default)
			)
			(layer "F.Fab")
		)
		(fp_line
			(start -0.2794 0.9906)
			(end 0.2794 0.9906)
			(stroke
				(width 0.1)
				(type default)
			)
			(layer "F.Fab")
		)
		(pad "1" smd rect
			(at 0 0 90)
			(size 0.508 0.508)
			(layers "F.Cu" "F.Mask" "F.Paste")
			(net "VR_PVDDQ_KLM_XADDR2")
		)
		(pad "2" smd rect
			(at 0 0.889 90)
			(size 0.508 0.508)
			(layers "F.Cu" "F.Mask" "F.Paste")
			(net "GND")
		)
		(zone
			(layer "F.Cu")
			(hatch none 0.5)
			(connect_pads
				(clearance 0)
			)
			(min_thickness 0.25)
			(keepout
				(tracks allowed)
				(vias not_allowed)
				(pads allowed)
				(copperpour not_allowed)
				(footprints allowed)
			)
			(placement
				(enabled no)
				(sheetname "")
			)
			(fill
				(thermal_gap 0.5)
				(thermal_bridge_width 0.5)
				(island_removal_mode 0)
			)
			(polygon
				(pts
					(xy 6.604 -124.841) (xy 6.604 -125.349) (xy 6.985 -125.349) (xy 6.985 -124.841)
				)
			)
		)
		(zone
			(layer "F.Cu")
			(hatch none 0.5)
			(connect_pads
				(clearance 0)
			)
			(min_thickness 0.25)
			(keepout
				(tracks not_allowed)
				(vias allowed)
				(pads allowed)
				(copperpour not_allowed)
				(footprints allowed)
			)
			(placement
				(enabled no)
				(sheetname "")
			)
			(fill
				(thermal_gap 0.5)
				(thermal_bridge_width 0.5)
				(island_removal_mode 0)
			)
			(polygon
				(pts
					(xy 6.985 -124.841) (xy 6.985 -125.349) (xy 6.604 -125.349) (xy 6.604 -124.841)
				)
			)
		)
	)
	(footprint ""
		(layer "F.Cu")
		(at 0.635 -143.256 -90)
		(property "Reference" "C1A6"
			(at 0 0 270)
			(layer "F.SilkS")
			(hide yes)
			(effects
				(font
					(size 1.27 1.27)
				)
			)
		)
		(property "Value" ""
			(at 0 0 270)
			(layer "F.Fab")
			(effects
				(font
					(size 1.27 1.27)
				)
			)
		)
		(duplicate_pad_numbers_are_jumpers no)
		(fp_poly
			(pts
				(xy 0.3048 -0.1016) (xy 0.3048 0.9906) (xy -0.3048 0.9906) (xy -0.3048 -0.1016)
			)
			(stroke
				(width 0)
				(type default)
			)
			(fill no)
			(layer "F.CrtYd")
		)
		(fp_line
			(start -0.3048 0.9906)
			(end 0.3048 0.9906)
			(stroke
				(width 0.1)
				(type default)
			)
			(layer "F.Fab")
		)
		(fp_line
			(start 0.3048 0.9906)
			(end 0.3048 -0.1016)
			(stroke
				(width 0.1)
				(type default)
			)
			(layer "F.Fab")
		)
		(fp_line
			(start -0.3048 -0.1016)
			(end -0.3048 0.9906)
			(stroke
				(width 0.1)
				(type default)
			)
			(layer "F.Fab")
		)
		(fp_line
			(start 0.3048 -0.1016)
			(end -0.3048 -0.1016)
			(stroke
				(width 0.1)
				(type default)
			)
			(layer "F.Fab")
		)
		(pad "1" smd rect
			(at 0 0 270)
			(size 0.508 0.508)
			(layers "F.Cu" "F.Mask" "F.Paste")
			(net "VR_PVDDQ_KLM_PH2_VCIN")
		)
		(pad "2" smd rect
			(at 0 0.889 270)
			(size 0.508 0.508)
			(layers "F.Cu" "F.Mask" "F.Paste")
			(net "GND")
		)
		(zone
			(layer "F.Cu")
			(hatch none 0.5)
			(connect_pads
				(clearance 0)
			)
			(min_thickness 0.25)
			(keepout
				(tracks not_allowed)
				(vias allowed)
				(pads allowed)
				(copperpour not_allowed)
				(footprints allowed)
			)
			(placement
				(enabled no)
				(sheetname "")
			)
			(fill
				(thermal_gap 0.5)
				(thermal_bridge_width 0.5)
				(island_removal_mode 0)
			)
			(polygon
				(pts
					(xy 0 -143.51) (xy 0 -143.002) (xy 0.381 -143.002) (xy 0.381 -143.51)
				)
			)
		)
		(zone
			(layer "F.Cu")
			(hatch none 0.5)
			(connect_pads
				(clearance 0)
			)
			(min_thickness 0.25)
			(keepout
				(tracks allowed)
				(vias not_allowed)
				(pads allowed)
				(copperpour not_allowed)
				(footprints allowed)
			)
			(placement
				(enabled no)
				(sheetname "")
			)
			(fill
				(thermal_gap 0.5)
				(thermal_bridge_width 0.5)
				(island_removal_mode 0)
			)
			(polygon
				(pts
					(xy 0.381 -143.51) (xy 0.381 -143.002) (xy 0 -143.002) (xy 0 -143.51)
				)
			)
		)
	)
	(footprint ""
		(layer "F.Cu")
		(at 380.032768 -33.7185 -90)
		(property "Reference" "C8F7"
			(at 0 0 270)
			(layer "F.SilkS")
			(hide yes)
			(effects
				(font
					(size 1.27 1.27)
				)
			)
		)
		(property "Value" ""
			(at 0 0 270)
			(layer "F.Fab")
			(effects
				(font
					(size 1.27 1.27)
				)
			)
		)
		(duplicate_pad_numbers_are_jumpers no)
		(fp_poly
			(pts
				(xy 0.3048 -0.1016) (xy 0.3048 0.9906) (xy -0.3048 0.9906) (xy -0.3048 -0.1016)
			)
			(stroke
				(width 0)
				(type default)
			)
			(fill no)
			(layer "F.CrtYd")
		)
		(fp_line
			(start -0.3048 0.9906)
			(end 0.3048 0.9906)
			(stroke
				(width 0.1)
				(type default)
			)
			(layer "F.Fab")
		)
		(fp_line
			(start 0.3048 0.9906)
			(end 0.3048 -0.1016)
			(stroke
				(width 0.1)
				(type default)
			)
			(layer "F.Fab")
		)
		(fp_line
			(start -0.3048 -0.1016)
			(end -0.3048 0.9906)
			(stroke
				(width 0.1)
				(type default)
			)
			(layer "F.Fab")
		)
		(fp_line
			(start 0.3048 -0.1016)
			(end -0.3048 -0.1016)
			(stroke
				(width 0.1)
				(type default)
			)
			(layer "F.Fab")
		)
		(pad "1" smd rect
			(at 0 0 270)
			(size 0.508 0.508)
			(layers "F.Cu" "F.Mask" "F.Paste")
			(net "P3E_PCH_TX_0_DP")
		)
		(pad "2" smd rect
			(at 0 0.889 270)
			(size 0.508 0.508)
			(layers "F.Cu" "F.Mask" "F.Paste")
			(net "P3E_PCH_M2_SATA6G_TX_R_DP")
		)
		(zone
			(layer "F.Cu")
			(hatch none 0.5)
			(connect_pads
				(clearance 0)
			)
			(min_thickness 0.25)
			(keepout
				(tracks not_allowed)
				(vias allowed)
				(pads allowed)
				(copperpour not_allowed)
				(footprints allowed)
			)
			(placement
				(enabled no)
				(sheetname "")
			)
			(fill
				(thermal_gap 0.5)
				(thermal_bridge_width 0.5)
				(island_removal_mode 0)
			)
			(polygon
				(pts
					(xy 379.397768 -33.9725) (xy 379.397768 -33.4645) (xy 379.778768 -33.4645) (xy 379.778768 -33.9725)
				)
			)
		)
		(zone
			(layer "F.Cu")
			(hatch none 0.5)
			(connect_pads
				(clearance 0)
			)
			(min_thickness 0.25)
			(keepout
				(tracks allowed)
				(vias not_allowed)
				(pads allowed)
				(copperpour not_allowed)
				(footprints allowed)
			)
			(placement
				(enabled no)
				(sheetname "")
			)
			(fill
				(thermal_gap 0.5)
				(thermal_bridge_width 0.5)
				(island_removal_mode 0)
			)
			(polygon
				(pts
					(xy 379.778768 -33.9725) (xy 379.778768 -33.4645) (xy 379.397768 -33.4645) (xy 379.397768 -33.9725)
				)
			)
		)
	)
	(footprint ""
		(layer "F.Cu")
		(at 429.26 -130.7465 180)
		(property "Reference" "R8E12"
			(at 0 0 180)
			(layer "F.SilkS")
			(hide yes)
			(effects
				(font
					(size 1.27 1.27)
				)
			)
		)
		(property "Value" ""
			(at 0 0 180)
			(layer "F.Fab")
			(effects
				(font
					(size 1.27 1.27)
				)
			)
		)
		(duplicate_pad_numbers_are_jumpers no)
		(fp_poly
			(pts
				(xy -0.2794 -0.1016) (xy 0.2794 -0.1016) (xy 0.2794 0.9906) (xy -0.2794 0.9906)
			)
			(stroke
				(width 0)
				(type default)
			)
			(fill no)
			(layer "F.CrtYd")
		)
		(fp_line
			(start 0.2794 0.9906)
			(end 0.2794 -0.1016)
			(stroke
				(width 0.1)
				(type default)
			)
			(layer "F.Fab")
		)
		(fp_line
			(start 0.2794 -0.1016)
			(end -0.2794 -0.1016)
			(stroke
				(width 0.1)
				(type default)
			)
			(layer "F.Fab")
		)
		(fp_line
			(start -0.2794 0.9906)
			(end 0.2794 0.9906)
			(stroke
				(width 0.1)
				(type default)
			)
			(layer "F.Fab")
		)
		(fp_line
			(start -0.2794 -0.1016)
			(end -0.2794 0.9906)
			(stroke
				(width 0.1)
				(type default)
			)
			(layer "F.Fab")
		)
		(pad "1" smd rect
			(at 0 0 180)
			(size 0.508 0.508)
			(layers "F.Cu" "F.Mask" "F.Paste")
			(net "P3V3_STBY")
		)
		(pad "2" smd rect
			(at 0 0.889 180)
			(size 0.508 0.508)
			(layers "F.Cu" "F.Mask" "F.Paste")
			(net "FM_CTNR_PS_ON")
		)
		(zone
			(layer "F.Cu")
			(hatch none 0.5)
			(connect_pads
				(clearance 0)
			)
			(min_thickness 0.25)
			(keepout
				(tracks not_allowed)
				(vias allowed)
				(pads allowed)
				(copperpour not_allowed)
				(footprints allowed)
			)
			(placement
				(enabled no)
				(sheetname "")
			)
			(fill
				(thermal_gap 0.5)
				(thermal_bridge_width 0.5)
				(island_removal_mode 0)
			)
			(polygon
				(pts
					(xy 429.514 -131.3815) (xy 429.006 -131.3815) (xy 429.006 -131.0005) (xy 429.514 -131.0005)
				)
			)
		)
		(zone
			(layer "F.Cu")
			(hatch none 0.5)
			(connect_pads
				(clearance 0)
			)
			(min_thickness 0.25)
			(keepout
				(tracks allowed)
				(vias not_allowed)
				(pads allowed)
				(copperpour not_allowed)
				(footprints allowed)
			)
			(placement
				(enabled no)
				(sheetname "")
			)
			(fill
				(thermal_gap 0.5)
				(thermal_bridge_width 0.5)
				(island_removal_mode 0)
			)
			(polygon
				(pts
					(xy 429.514 -131.0005) (xy 429.006 -131.0005) (xy 429.006 -131.3815) (xy 429.514 -131.3815)
				)
			)
		)
	)
	(footprint ""
		(layer "F.Cu")
		(at 192.786 -13.3985)
		(property "Reference" "R4G1"
			(at 0 0 0)
			(layer "F.SilkS")
			(hide yes)
			(effects
				(font
					(size 1.27 1.27)
				)
			)
		)
		(property "Value" ""
			(at 0 0 0)
			(layer "F.Fab")
			(effects
				(font
					(size 1.27 1.27)
				)
			)
		)
		(duplicate_pad_numbers_are_jumpers no)
		(fp_poly
			(pts
				(xy -0.2794 -0.1016) (xy 0.2794 -0.1016) (xy 0.2794 0.9906) (xy -0.2794 0.9906)
			)
			(stroke
				(width 0)
				(type default)
			)
			(fill no)
			(layer "F.CrtYd")
		)
		(fp_line
			(start -0.2794 -0.1016)
			(end -0.2794 0.9906)
			(stroke
				(width 0.1)
				(type default)
			)
			(layer "F.Fab")
		)
		(fp_line
			(start -0.2794 0.9906)
			(end 0.2794 0.9906)
			(stroke
				(width 0.1)
				(type default)
			)
			(layer "F.Fab")
		)
		(fp_line
			(start 0.2794 -0.1016)
			(end -0.2794 -0.1016)
			(stroke
				(width 0.1)
				(type default)
			)
			(layer "F.Fab")
		)
		(fp_line
			(start 0.2794 0.9906)
			(end 0.2794 -0.1016)
			(stroke
				(width 0.1)
				(type default)
			)
			(layer "F.Fab")
		)
		(pad "1" smd rect
			(at 0 0)
			(size 0.508 0.508)
			(layers "F.Cu" "F.Mask" "F.Paste")
			(net "M_B_CPU_VREF")
		)
		(pad "2" smd rect
			(at 0 0.889)
			(size 0.508 0.508)
			(layers "F.Cu" "F.Mask" "F.Paste")
			(net "M_B_VREF")
		)
		(zone
			(layer "F.Cu")
			(hatch none 0.5)
			(connect_pads
				(clearance 0)
			)
			(min_thickness 0.25)
			(keepout
				(tracks allowed)
				(vias not_allowed)
				(pads allowed)
				(copperpour not_allowed)
				(footprints allowed)
			)
			(placement
				(enabled no)
				(sheetname "")
			)
			(fill
				(thermal_gap 0.5)
				(thermal_bridge_width 0.5)
				(island_removal_mode 0)
			)
			(polygon
				(pts
					(xy 192.532 -13.1445) (xy 193.04 -13.1445) (xy 193.04 -12.7635) (xy 192.532 -12.7635)
				)
			)
		)
		(zone
			(layer "F.Cu")
			(hatch none 0.5)
			(connect_pads
				(clearance 0)
			)
			(min_thickness 0.25)
			(keepout
				(tracks not_allowed)
				(vias allowed)
				(pads allowed)
				(copperpour not_allowed)
				(footprints allowed)
			)
			(placement
				(enabled no)
				(sheetname "")
			)
			(fill
				(thermal_gap 0.5)
				(thermal_bridge_width 0.5)
				(island_removal_mode 0)
			)
			(polygon
				(pts
					(xy 192.532 -12.7635) (xy 193.04 -12.7635) (xy 193.04 -13.1445) (xy 192.532 -13.1445)
				)
			)
		)
	)
	(footprint ""
		(layer "F.Cu")
		(at 18.923 -79.629 180)
		(property "Reference" "C1D11"
			(at 0 0 180)
			(layer "F.SilkS")
			(hide yes)
			(effects
				(font
					(size 1.27 1.27)
				)
			)
		)
		(property "Value" ""
			(at 0 0 180)
			(layer "F.Fab")
			(effects
				(font
					(size 1.27 1.27)
				)
			)
		)
		(duplicate_pad_numbers_are_jumpers no)
		(fp_rect
			(start -0.3048 -0.1016)
			(end 0.3048 0.9906)
			(stroke
				(width 0)
				(type default)
			)
			(fill no)
			(layer "F.CrtYd")
		)
		(fp_line
			(start 0.3048 0.9906)
			(end 0.3048 -0.1016)
			(stroke
				(width 0.1)
				(type default)
			)
			(layer "F.Fab")
		)
		(fp_line
			(start 0.3048 -0.1016)
			(end -0.3048 -0.1016)
			(stroke
				(width 0.1)
				(type default)
			)
			(layer "F.Fab")
		)
		(fp_line
			(start -0.3048 0.9906)
			(end 0.3048 0.9906)
			(stroke
				(width 0.1)
				(type default)
			)
			(layer "F.Fab")
		)
		(fp_line
			(start -0.3048 -0.1016)
			(end -0.3048 0.9906)
			(stroke
				(width 0.1)
				(type default)
			)
			(layer "F.Fab")
		)
		(pad "1" smd rect
			(at 0 0 180)
			(size 0.508 0.508)
			(layers "F.Cu" "F.Mask" "F.Paste")
			(net "FM_P12V_HOTSWAP0_EN")
		)
		(pad "2" smd rect
			(at 0 0.889 180)
			(size 0.508 0.508)
			(layers "F.Cu" "F.Mask" "F.Paste")
			(net "AGND_HSC")
		)
		(zone
			(layer "F.Cu")
			(hatch none 0.5)
			(connect_pads
				(clearance 0)
			)
			(min_thickness 0.25)
			(keepout
				(tracks allowed)
				(vias not_allowed)
				(pads allowed)
				(copperpour not_allowed)
				(footprints allowed)
			)
			(placement
				(enabled no)
				(sheetname "")
			)
			(fill
				(thermal_gap 0.5)
				(thermal_bridge_width 0.5)
				(island_removal_mode 0)
			)
			(polygon
				(pts
					(xy 19.177 -79.883) (xy 19.177 -80.264) (xy 18.669 -80.264) (xy 18.669 -79.883)
				)
			)
		)
		(zone
			(layer "F.Cu")
			(hatch none 0.5)
			(connect_pads
				(clearance 0)
			)
			(min_thickness 0.25)
			(keepout
				(tracks not_allowed)
				(vias allowed)
				(pads allowed)
				(copperpour not_allowed)
				(footprints allowed)
			)
			(placement
				(enabled no)
				(sheetname "")
			)
			(fill
				(thermal_gap 0.5)
				(thermal_bridge_width 0.5)
				(island_removal_mode 0)
			)
			(polygon
				(pts
					(xy 19.177 -79.883) (xy 19.177 -80.264) (xy 18.669 -80.264) (xy 18.669 -79.883)
				)
			)
		)
	)
	(footprint ""
		(layer "F.Cu")
		(at 210.058 -45.974)
		(property "Reference" ""
			(at 0 0 0)
			(layer "F.SilkS")
			(hide yes)
			(effects
				(font
					(size 1.27 1.27)
				)
			)
		)
		(property "Value" ""
			(at 0 0 0)
			(layer "F.Fab")
			(effects
				(font
					(size 1.27 1.27)
				)
			)
		)
		(duplicate_pad_numbers_are_jumpers no)
		(fp_poly
			(pts
				(arc
					(start 2.032 0)
					(mid -2.032 0)
					(end 2.032 0)
				)
			)
			(stroke
				(width 0)
				(type default)
			)
			(fill no)
			(layer "F.CrtYd")
		)
		(pad "1" smd circle
			(at 0 0)
			(size 1.016 1.016)
			(layers "F.Cu" "F.Mask" "F.Paste")
			(net "Net_395")
		)
		(zone
			(layer "F.Cu")
			(hatch none 0.5)
			(connect_pads
				(clearance 0)
			)
			(min_thickness 0.25)
			(keepout
				(tracks not_allowed)
				(vias allowed)
				(pads allowed)
				(copperpour not_allowed)
				(footprints allowed)
			)
			(placement
				(enabled no)
				(sheetname "")
			)
			(fill
				(thermal_gap 0.5)
				(thermal_bridge_width 0.5)
				(island_removal_mode 0)
			)
			(polygon
				(pts
					(arc
						(start 211.582 -45.974)
						(mid 208.534 -45.974)
						(end 211.582 -45.974)
					)
				)
			)
		)
		(zone
			(layers "F.Cu" "B.Cu" "In1.Cu" "In2.Cu" "In3.Cu" "In4.Cu" "In5.Cu" "In6.Cu"
				"In7.Cu" "In8.Cu" "In9.Cu" "In10.Cu" "In11.Cu" "In12.Cu"
			)
			(hatch none 0.5)
			(connect_pads
				(clearance 0)
			)
			(min_thickness 0.25)
			(keepout
				(tracks allowed)
				(vias not_allowed)
				(pads allowed)
				(copperpour not_allowed)
				(footprints allowed)
			)
			(placement
				(enabled no)
				(sheetname "")
			)
			(fill
				(thermal_gap 0.5)
				(thermal_bridge_width 0.5)
				(island_removal_mode 0)
			)
			(polygon
				(pts
					(arc
						(start 211.582 -45.974)
						(mid 208.534 -45.974)
						(end 211.582 -45.974)
					)
				)
			)
		)
	)
	(footprint ""
		(layer "F.Cu")
		(at 407.631392 -10.916666)
		(property "Reference" "C8G7"
			(at 0 0 0)
			(layer "F.SilkS")
			(hide yes)
			(effects
				(font
					(size 1.27 1.27)
				)
			)
		)
		(property "Value" ""
			(at 0 0 0)
			(layer "F.Fab")
			(effects
				(font
					(size 1.27 1.27)
				)
			)
		)
		(duplicate_pad_numbers_are_jumpers no)
		(fp_rect
			(start -0.3048 0.9906)
			(end 0.3048 -0.1016)
			(stroke
				(width 0)
				(type default)
			)
			(fill no)
			(layer "F.CrtYd")
		)
		(fp_line
			(start -0.3048 -0.1016)
			(end -0.3048 0.9906)
			(stroke
				(width 0.1)
				(type default)
			)
			(layer "F.Fab")
		)
		(fp_line
			(start -0.3048 0.9906)
			(end 0.3048 0.9906)
			(stroke
				(width 0.1)
				(type default)
			)
			(layer "F.Fab")
		)
		(fp_line
			(start 0.3048 -0.1016)
			(end -0.3048 -0.1016)
			(stroke
				(width 0.1)
				(type default)
			)
			(layer "F.Fab")
		)
		(fp_line
			(start 0.3048 0.9906)
			(end 0.3048 -0.1016)
			(stroke
				(width 0.1)
				(type default)
			)
			(layer "F.Fab")
		)
		(pad "1" smd rect
			(at 0 0)
			(size 0.508 0.508)
			(layers "F.Cu" "F.Mask" "F.Paste")
			(net "P3E_CPU0_PE2_SS_TXN<1>")
		)
		(pad "2" smd rect
			(at 0 0.889)
			(size 0.508 0.508)
			(layers "F.Cu" "F.Mask" "F.Paste")
			(net "P3E_CPU0_PE2_SS_C_TXN<1>")
		)
		(zone
			(layer "F.Cu")
			(hatch none 0.5)
			(connect_pads
				(clearance 0)
			)
			(min_thickness 0.25)
			(keepout
				(tracks allowed)
				(vias not_allowed)
				(pads allowed)
				(copperpour not_allowed)
				(footprints allowed)
			)
			(placement
				(enabled no)
				(sheetname "")
			)
			(fill
				(thermal_gap 0.5)
				(thermal_bridge_width 0.5)
				(island_removal_mode 0)
			)
			(polygon
				(pts
					(xy 407.377392 -10.281666) (xy 407.885392 -10.281666) (xy 407.885392 -10.662666) (xy 407.377392 -10.662666)
				)
			)
		)
	)
)
